# S9S_MB_2U (Grand Teton) — schematic netlist excerpt (pin names and nets, part order shuffled) for the footprints in the layout excerpt that follows; sources: Cadence DE-HDL packaged netlist, KiCad conversion of 03242023_DA0F0TMBIJ0_F0T_Motherboard_J_brd_V01_OCP.brd

R4503  Q_RES  0 5% CHIP  pkg 0402LF  page 131 : A = SMB_HOST_3V3AUX_SDA_R4 ; B = SMB_HOST_3V3AUX_XDP_R_SDA
R630  Q_RES  10K 1% EMPTY  pkg 0402LF  page 127 : A = PU_PIROM_CPU1_ADDR0 ; B = GND
C723  Q_CAP_DIFFBUS  DIFF BUS_0.22UF 6.3V 20% X6S  pkg C0201  page 176 : \1\ = P5E_CPU1_PE0_TX_C_DP<9> ; \2\ = P5E_CPU1_PE0_TX_DP<9>

(kicad_pcb
	(version 20260206)
	(generator "pcbnew")
	(generator_version "10.0")
	(general
		(thickness 1.6)
		(legacy_teardrops no)
	)
	(paper "A4")
	(title_block
		(title "03242023_DA0F0TMBIJ0_F0T_Motherboard_J_brd_V01_OCP.brd")
		(comment 1 "Grand Teton / footprints 1504-1506 of 6105")
	)
	(layers
		(0 "F.Cu" signal "TOP")
		(4 "In1.Cu" signal "GND")
		(6 "In2.Cu" signal "IN1")
		(8 "In3.Cu" signal "GND1")
		(10 "In4.Cu" signal "IN2")
		(12 "In5.Cu" signal "GND2")
		(14 "In6.Cu" signal "IN3")
		(16 "In7.Cu" signal "GND3")
		(18 "In8.Cu" signal "VCC")
		(20 "In9.Cu" signal "VCC1")
		(22 "In10.Cu" signal "GND4")
		(24 "In11.Cu" signal "IN4")
		(26 "In12.Cu" signal "GND5")
		(28 "In13.Cu" signal "IN5")
		(30 "In14.Cu" signal "GND6")
		(32 "In15.Cu" signal "IN6")
		(34 "In16.Cu" signal "GND7")
		(2 "B.Cu" signal "BOTTOM")
		(9 "F.Adhes" user "F.Adhesive")
		(11 "B.Adhes" user "B.Adhesive")
		(13 "F.Paste" user "Package Geometry/Pastemask Top")
		(15 "B.Paste" user "Package Geometry/Pastemask Bottom")
		(5 "F.SilkS" user "Ref Des/Silkscreen Top")
		(7 "B.SilkS" user "Ref Des/Silkscreen Bottom")
		(1 "F.Mask" user "Board Geometry/Soldermask Top")
		(3 "B.Mask" user "Board Geometry/Soldermask Bottom")
		(17 "Dwgs.User" user "User.Drawings")
		(19 "Cmts.User" user "User.Comments")
		(21 "Eco1.User" user "User.Eco1")
		(23 "Eco2.User" user "User.Eco2")
		(25 "Edge.Cuts" user "Board Geometry/Outline")
		(27 "Margin" user)
		(31 "F.CrtYd" user "Package Geometry/Place Bound Top")
		(29 "B.CrtYd" user "Package Geometry/Place Bound Bottom")
		(35 "F.Fab" user "Ref Des/Assembly Top")
		(33 "B.Fab" user "Ref Des/Assembly Bottom")
	)
	(footprint ""
		(layer "F.Cu")
		(at 193.93408 -353.761548)
		(property "Reference" "R630"
			(at 0 0 0)
			(layer "F.SilkS")
			(hide yes)
			(effects
				(font
					(size 1.27 1.27)
				)
			)
		)
		(property "Value" ""
			(at 0 0 0)
			(layer "F.Fab")
			(effects
				(font
					(size 1.27 1.27)
				)
			)
		)
		(duplicate_pad_numbers_are_jumpers no)
		(fp_line
			(start -0.7874 -0.4064)
			(end 0.7874 -0.4064)
			(stroke
				(width 0.1524)
				(type default)
			)
			(layer "F.SilkS")
		)
		(fp_line
			(start -0.7874 0.4064)
			(end -0.7874 -0.4064)
			(stroke
				(width 0.1524)
				(type default)
			)
			(layer "F.SilkS")
		)
		(fp_line
			(start 0.7874 -0.4064)
			(end 0.7874 0.4064)
			(stroke
				(width 0.1524)
				(type default)
			)
			(layer "F.SilkS")
		)
		(fp_line
			(start 0.7874 0.4064)
			(end -0.7874 0.4064)
			(stroke
				(width 0.1524)
				(type default)
			)
			(layer "F.SilkS")
		)
		(fp_line
			(start -0.67945 -0.305054)
			(end -0.12065 -0.305054)
			(stroke
				(width 0.1)
				(type default)
			)
			(layer "F.Fab")
		)
		(fp_line
			(start -0.67945 0.3048)
			(end -0.67945 -0.305054)
			(stroke
				(width 0.1)
				(type default)
			)
			(layer "F.Fab")
		)
		(fp_line
			(start -0.12065 -0.305054)
			(end -0.12065 -0.2794)
			(stroke
				(width 0.1)
				(type default)
			)
			(layer "F.Fab")
		)
		(fp_line
			(start -0.12065 -0.2794)
			(end 0.12065 -0.2794)
			(stroke
				(width 0.1)
				(type default)
			)
			(layer "F.Fab")
		)
		(fp_line
			(start -0.12065 0.2794)
			(end -0.12065 0.3048)
			(stroke
				(width 0.1)
				(type default)
			)
			(layer "F.Fab")
		)
		(fp_line
			(start -0.12065 0.3048)
			(end -0.67945 0.3048)
			(stroke
				(width 0.1)
				(type default)
			)
			(layer "F.Fab")
		)
		(fp_line
			(start 0.120396 0.2794)
			(end -0.12065 0.2794)
			(stroke
				(width 0.1)
				(type default)
			)
			(layer "F.Fab")
		)
		(fp_line
			(start 0.120396 0.3048)
			(end 0.120396 0.2794)
			(stroke
				(width 0.1)
				(type default)
			)
			(layer "F.Fab")
		)
		(fp_line
			(start 0.12065 -0.3048)
			(end 0.67945 -0.3048)
			(stroke
				(width 0.1)
				(type default)
			)
			(layer "F.Fab")
		)
		(fp_line
			(start 0.12065 -0.2794)
			(end 0.12065 -0.3048)
			(stroke
				(width 0.1)
				(type default)
			)
			(layer "F.Fab")
		)
		(fp_line
			(start 0.67945 -0.3048)
			(end 0.67945 0.3048)
			(stroke
				(width 0.1)
				(type default)
			)
			(layer "F.Fab")
		)
		(fp_line
			(start 0.67945 0.3048)
			(end 0.120396 0.3048)
			(stroke
				(width 0.1)
				(type default)
			)
			(layer "F.Fab")
		)
		(pad "1" smd circle
			(at -0.40005 0)
			(size 0 0)
			(layers "F.Cu" "F.Mask" "F.Paste")
			(net "PU_PIROM_CPU1_ADDR0")
		)
		(pad "2" smd circle
			(at 0.40005 0)
			(size 0 0)
			(layers "F.Cu" "F.Mask" "F.Paste")
			(net "GND")
		)
	)
	(footprint ""
		(layer "F.Cu")
		(at 67.248278 -402.371052 -90)
		(property "Reference" "C723"
			(at 0 0 270)
			(layer "F.SilkS")
			(hide yes)
			(effects
				(font
					(size 1.27 1.27)
				)
			)
		)
		(property "Value" ""
			(at 0 0 270)
			(layer "F.Fab")
			(effects
				(font
					(size 1.27 1.27)
				)
			)
		)
		(duplicate_pad_numbers_are_jumpers no)
		(fp_line
			(start -0.299974 0.150114)
			(end -0.299974 -0.150114)
			(stroke
				(width 0.1)
				(type default)
			)
			(layer "F.Fab")
		)
		(fp_line
			(start 0.299974 0.150114)
			(end -0.299974 0.150114)
			(stroke
				(width 0.1)
				(type default)
			)
			(layer "F.Fab")
		)
		(fp_line
			(start -0.299974 -0.150114)
			(end 0.299974 -0.150114)
			(stroke
				(width 0.1)
				(type default)
			)
			(layer "F.Fab")
		)
		(fp_line
			(start 0.299974 -0.150114)
			(end 0.299974 0.150114)
			(stroke
				(width 0.1)
				(type default)
			)
			(layer "F.Fab")
		)
		(pad "1" smd rect
			(at -0.2667 0 270)
			(size 0.3048 0.381)
			(layers "F.Cu" "F.Mask" "F.Paste")
			(net "P5E_CPU1_PE0_TX_C_DP<9>")
		)
		(pad "2" smd rect
			(at 0.2667 0 270)
			(size 0.3048 0.381)
			(layers "F.Cu" "F.Mask" "F.Paste")
			(net "P5E_CPU1_PE0_TX_DP<9>")
		)
	)
	(footprint ""
		(layer "F.Cu")
		(at 403.987 -50.637948 180)
		(property "Reference" "R4503"
			(at 0 0 180)
			(layer "F.SilkS")
			(hide yes)
			(effects
				(font
					(size 1.27 1.27)
				)
			)
		)
		(property "Value" ""
			(at 0 0 180)
			(layer "F.Fab")
			(effects
				(font
					(size 1.27 1.27)
				)
			)
		)
		(duplicate_pad_numbers_are_jumpers no)
		(fp_line
			(start 0.7874 0.4064)
			(end -0.7874 0.4064)
			(stroke
				(width 0.1524)
				(type default)
			)
			(layer "F.SilkS")
		)
		(fp_line
			(start 0.7874 -0.4064)
			(end 0.7874 0.4064)
			(stroke
				(width 0.1524)
				(type default)
			)
			(layer "F.SilkS")
		)
		(fp_line
			(start -0.7874 0.4064)
			(end -0.7874 -0.4064)
			(stroke
				(width 0.1524)
				(type default)
			)
			(layer "F.SilkS")
		)
		(fp_line
			(start -0.7874 -0.4064)
			(end 0.7874 -0.4064)
			(stroke
				(width 0.1524)
				(type default)
			)
			(layer "F.SilkS")
		)
		(fp_line
			(start 0.67945 0.3048)
			(end 0.120396 0.3048)
			(stroke
				(width 0.1)
				(type default)
			)
			(layer "F.Fab")
		)
		(fp_line
			(start 0.67945 -0.3048)
			(end 0.67945 0.3048)
			(stroke
				(width 0.1)
				(type default)
			)
			(layer "F.Fab")
		)
		(fp_line
			(start 0.12065 -0.2794)
			(end 0.12065 -0.3048)
			(stroke
				(width 0.1)
				(type default)
			)
			(layer "F.Fab")
		)
		(fp_line
			(start 0.12065 -0.3048)
			(end 0.67945 -0.3048)
			(stroke
				(width 0.1)
				(type default)
			)
			(layer "F.Fab")
		)
		(fp_line
			(start 0.120396 0.3048)
			(end 0.120396 0.2794)
			(stroke
				(width 0.1)
				(type default)
			)
			(layer "F.Fab")
		)
		(fp_line
			(start 0.120396 0.2794)
			(end -0.12065 0.2794)
			(stroke
				(width 0.1)
				(type default)
			)
			(layer "F.Fab")
		)
		(fp_line
			(start -0.12065 0.3048)
			(end -0.67945 0.3048)
			(stroke
				(width 0.1)
				(type default)
			)
			(layer "F.Fab")
		)
		(fp_line
			(start -0.12065 0.2794)
			(end -0.12065 0.3048)
			(stroke
				(width 0.1)
				(type default)
			)
			(layer "F.Fab")
		)
		(fp_line
			(start -0.12065 -0.2794)
			(end 0.12065 -0.2794)
			(stroke
				(width 0.1)
				(type default)
			)
			(layer "F.Fab")
		)
		(fp_line
			(start -0.12065 -0.305054)
			(end -0.12065 -0.2794)
			(stroke
				(width 0.1)
				(type default)
			)
			(layer "F.Fab")
		)
		(fp_line
			(start -0.67945 0.3048)
			(end -0.67945 -0.305054)
			(stroke
				(width 0.1)
				(type default)
			)
			(layer "F.Fab")
		)
		(fp_line
			(start -0.67945 -0.305054)
			(end -0.12065 -0.305054)
			(stroke
				(width 0.1)
				(type default)
			)
			(layer "F.Fab")
		)
		(pad "1" smd circle
			(at -0.40005 0 180)
			(size 0 0)
			(layers "F.Cu" "F.Mask" "F.Paste")
			(net "SMB_HOST_3V3AUX_SDA_R4")
		)
		(pad "2" smd circle
			(at 0.40005 0 180)
			(size 0 0)
			(layers "F.Cu" "F.Mask" "F.Paste")
			(net "SMB_HOST_3V3AUX_XDP_R_SDA")
		)
	)
)
